(kicad_pcb
	(version 20241229)
	(generator "pcbnew")
	(generator_version "9.0")
	(general
		(thickness 1.552)
		(legacy_teardrops no)
	)
	(paper "A4")
	(title_block
		(date "2023-07-25")
		(rev "1.1.4")
		(comment 9 "footprints 154-158 of 379")
	)
	(layers
		(0 "F.Cu" signal)
		(4 "In1.Cu" signal)
		(6 "In2.Cu" signal)
		(8 "In3.Cu" signal)
		(10 "In4.Cu" signal)
		(12 "In5.Cu" signal)
		(14 "In6.Cu" signal)
		(2 "B.Cu" signal)
		(9 "F.Adhes" user "F.Adhesive")
		(11 "B.Adhes" user "B.Adhesive")
		(13 "F.Paste" user)
		(15 "B.Paste" user)
		(5 "F.SilkS" user "F.Silkscreen")
		(7 "B.SilkS" user "B.Silkscreen")
		(1 "F.Mask" user)
		(3 "B.Mask" user)
		(17 "Dwgs.User" user "User.Drawings")
		(19 "Cmts.User" user "User.Comments")
		(21 "Eco1.User" user "User.Eco1")
		(23 "Eco2.User" user "User.Eco2")
		(25 "Edge.Cuts" user)
		(27 "Margin" user)
		(31 "F.CrtYd" user "F.Courtyard")
		(29 "B.CrtYd" user "B.Courtyard")
		(35 "F.Fab" user)
		(33 "B.Fab" user)
	)
	(footprint "antmicro-footprints:SW_B3U-3000PM_SMD"
		(layer "F.Cu")
		(at 143.83 122.74)
		(property "Reference" "S1"
			(at 3.2 0.2 90)
			(layer "F.SilkS")
			(effects
				(font
					(size 0.65 0.65)
					(thickness 0.15)
				)
				(justify left bottom)
			)
		)
		(property "Value" "SW_B3U-3000PM"
			(at 0 2.8 0)
			(layer "F.Fab")
			(hide yes)
			(effects
				(font
					(size 0.7 0.7)
					(thickness 0.15)
				)
				(justify left bottom)
			)
		)
		(property "Datasheet" "http://www.farnell.com/datasheets/2610940.pdf"
			(at 0 0 0)
			(layer "F.Fab")
			(hide yes)
			(effects
				(font
					(size 1.27 1.27)
					(thickness 0.15)
				)
			)
		)
		(property "Description" "Tactile Switch SPST-NO Side Actuated Surface Mount, Right Angle"
			(at 0 0 0)
			(layer "F.Fab")
			(hide yes)
			(effects
				(font
					(size 1.27 1.27)
					(thickness 0.15)
				)
			)
		)
		(property "Author" "Antmicro"
			(at 0 0 0)
			(layer "F.Fab")
			(hide yes)
			(effects
				(font
					(size 1 1)
					(thickness 0.15)
				)
			)
		)
		(property "License" "Apache-2.0"
			(at 0 0 0)
			(layer "F.Fab")
			(hide yes)
			(effects
				(font
					(size 1 1)
					(thickness 0.15)
				)
			)
		)
		(property "MPN" "B3U-3000PM"
			(at 0 0 0)
			(layer "F.Fab")
			(hide yes)
			(effects
				(font
					(size 1 1)
					(thickness 0.15)
				)
			)
		)
		(property "Manufacturer" "Omron"
			(at 0 0 0)
			(layer "F.Fab")
			(hide yes)
			(effects
				(font
					(size 1 1)
					(thickness 0.15)
				)
			)
		)
		(sheetname "/FPGA/")
		(sheetfile "fpga.kicad_sch")
		(attr smd)
		(fp_line
			(start -1.5 -1.299)
			(end -1.5 -1.599)
			(stroke
				(width 0.15)
				(type solid)
			)
			(layer "F.SilkS")
		)
		(fp_line
			(start -1.5 0.9)
			(end -1.5 0.6)
			(stroke
				(width 0.15)
				(type solid)
			)
			(layer "F.SilkS")
		)
		(fp_line
			(start -1.5 0.9)
			(end 1.5 0.9)
			(stroke
				(width 0.15)
				(type solid)
			)
			(layer "F.SilkS")
		)
		(fp_line
			(start -0.9 0.9)
			(end -0.9 1.301)
			(stroke
				(width 0.15)
				(type solid)
			)
			(layer "F.SilkS")
		)
		(fp_line
			(start -0.5 1.651)
			(end -0.9 1.301)
			(stroke
				(width 0.15)
				(type solid)
			)
			(layer "F.SilkS")
		)
		(fp_line
			(start 0.5 1.651)
			(end -0.5 1.651)
			(stroke
				(width 0.15)
				(type solid)
			)
			(layer "F.SilkS")
		)
		(fp_line
			(start 0.5 1.651)
			(end 0.9 1.301)
			(stroke
				(width 0.15)
				(type solid)
			)
			(layer "F.SilkS")
		)
		(fp_line
			(start 0.9 0.9)
			(end 0.9 1.301)
			(stroke
				(width 0.15)
				(type solid)
			)
			(layer "F.SilkS")
		)
		(fp_line
			(start 1.5 -1.599)
			(end -1.501 -1.599)
			(stroke
				(width 0.15)
				(type solid)
			)
			(layer "F.SilkS")
		)
		(fp_line
			(start 1.5 -1.299)
			(end 1.5 -1.599)
			(stroke
				(width 0.15)
				(type solid)
			)
			(layer "F.SilkS")
		)
		(fp_line
			(start 1.5 0.9)
			(end 1.5 0.6)
			(stroke
				(width 0.15)
				(type solid)
			)
			(layer "F.SilkS")
		)
		(fp_rect
			(start -2.4 -1.9)
			(end 2.4 1.9)
			(stroke
				(width 0.05)
				(type solid)
			)
			(fill no)
			(layer "F.CrtYd")
		)
		(fp_line
			(start -0.9 -1.6)
			(end -1.5 -1)
			(stroke
				(width 0.15)
				(type solid)
			)
			(layer "F.Fab")
		)
		(fp_line
			(start -0.9 0.9)
			(end -0.9 1.301)
			(stroke
				(width 0.15)
				(type solid)
			)
			(layer "F.Fab")
		)
		(fp_line
			(start -0.5 1.651)
			(end -0.9 1.301)
			(stroke
				(width 0.15)
				(type solid)
			)
			(layer "F.Fab")
		)
		(fp_line
			(start 0.5 1.651)
			(end -0.5 1.651)
			(stroke
				(width 0.15)
				(type solid)
			)
			(layer "F.Fab")
		)
		(fp_line
			(start 0.5 1.651)
			(end 0.9 1.301)
			(stroke
				(width 0.15)
				(type solid)
			)
			(layer "F.Fab")
		)
		(fp_line
			(start 0.9 0.9)
			(end 0.9 1.301)
			(stroke
				(width 0.15)
				(type solid)
			)
			(layer "F.Fab")
		)
		(fp_rect
			(start -1.5 -1.6)
			(end 1.5 0.9)
			(stroke
				(width 0.15)
				(type solid)
			)
			(fill no)
			(layer "F.Fab")
		)
		(fp_text user "License: Apache-2.0"
			(at -2.4 6.849 0)
			(layer "F.Fab")
			(effects
				(font
					(size 0.7 0.7)
					(thickness 0.15)
				)
				(justify left bottom)
			)
		)
		(fp_text user "Author: Antmicro"
			(at -2.4 5.649 0)
			(layer "F.Fab")
			(effects
				(font
					(size 0.7 0.7)
					(thickness 0.15)
				)
				(justify left bottom)
			)
		)
		(fp_text user "${REFERENCE}"
			(at -2.4 4.448 0)
			(layer "F.Fab")
			(effects
				(font
					(size 0.7 0.7)
					(thickness 0.15)
				)
				(justify left bottom)
			)
		)
		(pad "1" smd rect
			(at -1.7 -0.35)
			(size 0.8 1.7)
			(layers "F.Cu" "F.Mask" "F.Paste")
			(net 1 "GND")
			(pinfunction "1")
			(pintype "passive")
		)
		(pad "2" smd rect
			(at 1.7 -0.35)
			(size 0.8 1.7)
			(layers "F.Cu" "F.Mask" "F.Paste")
			(net 281 "Net-(R72-Pad2)")
			(pinfunction "2")
			(pintype "passive")
		)
	)
	(footprint "antmicro-footprints:TSOT23-6"
		(layer "F.Cu")
		(at 142.989 69.204 180)
		(property "Reference" "U5"
			(at 1.059 2.144 0)
			(layer "F.SilkS")
			(effects
				(font
					(size 0.65 0.65)
					(thickness 0.15)
				)
				(justify right top)
			)
		)
		(property "Value" "AP62301WU-7"
			(at -0.005 2.6 0)
			(layer "F.Fab")
			(hide yes)
			(effects
				(font
					(size 0.7 0.7)
					(thickness 0.15)
				)
				(justify right top)
			)
		)
		(property "Datasheet" "https://www.diodes.com/assets/Datasheets/AP62300_AP62301_AP62300T.pdf"
			(at 0 0 0)
			(layer "F.Fab")
			(hide yes)
			(effects
				(font
					(size 1.27 1.27)
					(thickness 0.15)
				)
			)
		)
		(property "Description" "DC-DC Switching Synchronous Buck Regulator, Adjustable, 4.2V-18Vin, 0.8V-7V/3A out, TSOT-26-6"
			(at 0 0 0)
			(layer "F.Fab")
			(hide yes)
			(effects
				(font
					(size 1.27 1.27)
					(thickness 0.15)
				)
			)
		)
		(property "Author" "Antmicro"
			(at 212.17 -73.79 90)
			(layer "F.Fab")
			(hide yes)
			(effects
				(font
					(size 1 1)
					(thickness 0.15)
				)
			)
		)
		(property "License" "Apache-2.0"
			(at 212.17 -73.79 90)
			(layer "F.Fab")
			(hide yes)
			(effects
				(font
					(size 1 1)
					(thickness 0.15)
				)
			)
		)
		(property "MPN" "AP62301WU-7"
			(at 212.17 -73.79 90)
			(layer "F.Fab")
			(hide yes)
			(effects
				(font
					(size 1 1)
					(thickness 0.15)
				)
			)
		)
		(property "Manufacturer" "Diodes Incorporated"
			(at 212.17 -73.79 90)
			(layer "F.Fab")
			(hide yes)
			(effects
				(font
					(size 1 1)
					(thickness 0.15)
				)
			)
		)
		(sheetname "/Power Supply/")
		(sheetfile "supply.kicad_sch")
		(attr smd)
		(fp_line
			(start 1 1.55)
			(end 1 1.4)
			(stroke
				(width 0.15)
				(type solid)
			)
			(layer "F.SilkS")
		)
		(fp_line
			(start 1 1.55)
			(end -1 1.55)
			(stroke
				(width 0.15)
				(type solid)
			)
			(layer "F.SilkS")
		)
		(fp_line
			(start 1 -1.497)
			(end 1 -1.375)
			(stroke
				(width 0.15)
				(type solid)
			)
			(layer "F.SilkS")
		)
		(fp_line
			(start 1 -1.497)
			(end -1 -1.5)
			(stroke
				(width 0.15)
				(type solid)
			)
			(layer "F.SilkS")
		)
		(fp_line
			(start -1 1.55)
			(end -1 1.4)
			(stroke
				(width 0.15)
				(type solid)
			)
			(layer "F.SilkS")
		)
		(fp_line
			(start -1 -1.5)
			(end -1 -1.375)
			(stroke
				(width 0.15)
				(type solid)
			)
			(layer "F.SilkS")
		)
		(fp_circle
			(center -1.44 -1.5)
			(end -1.39 -1.5)
			(stroke
				(width 0.15)
				(type solid)
			)
			(fill yes)
			(layer "F.SilkS")
		)
		(fp_rect
			(start 1.93 -1.7)
			(end -1.93 1.7)
			(stroke
				(width 0.05)
				(type solid)
			)
			(fill no)
			(layer "F.CrtYd")
		)
		(fp_line
			(start -0.45 -1.521)
			(end -0.876 -1.096)
			(stroke
				(width 0.15)
				(type solid)
			)
			(layer "F.Fab")
		)
		(fp_rect
			(start 0.875 1.528)
			(end -0.875 -1.525)
			(stroke
				(width 0.15)
				(type solid)
			)
			(fill no)
			(layer "F.Fab")
		)
		(fp_text user "License: Apache-2.0"
			(at -1.93 6.199 0)
			(layer "F.Fab")
			(effects
				(font
					(size 0.7 0.7)
					(thickness 0.15)
				)
				(justify right top)
			)
		)
		(fp_text user "Author: Antmicro"
			(at -1.93 5 0)
			(layer "F.Fab")
			(effects
				(font
					(size 0.7 0.7)
					(thickness 0.15)
				)
				(justify right top)
			)
		)
		(fp_text user "${REFERENCE}"
			(at -1.93 3.8 0)
			(layer "F.Fab")
			(effects
				(font
					(size 0.7 0.7)
					(thickness 0.15)
				)
				(justify right top)
			)
		)
		(pad "1" smd rect
			(at -1.301 -0.947 90)
			(size 0.7 1.2)
			(layers "F.Cu" "F.Mask" "F.Paste")
			(net 1 "GND")
			(pinfunction "GND")
			(pintype "power_in")
		)
		(pad "2" smd rect
			(at -1.301 0.004 90)
			(size 0.7 1.2)
			(layers "F.Cu" "F.Mask" "F.Paste")
			(net 276 "/Power Supply/1V0_SW")
			(pinfunction "SW")
			(pintype "power_out")
		)
		(pad "3" smd rect
			(at -1.301 0.954 90)
			(size 0.7 1.2)
			(layers "F.Cu" "F.Mask" "F.Paste")
			(net 326 "/Power Supply/5V_1V0_IN")
			(pinfunction "VIN")
			(pintype "power_in")
		)
		(pad "4" smd rect
			(at 1.299 0.954 90)
			(size 0.7 1.2)
			(layers "F.Cu" "F.Mask" "F.Paste")
			(net 267 "Net-(U5-FB)")
			(pinfunction "FB")
			(pintype "input")
		)
		(pad "5" smd rect
			(at 1.299 0.004 90)
			(size 0.7 1.2)
			(layers "F.Cu" "F.Mask" "F.Paste")
			(net 373 "Net-(U5-EN)")
			(pinfunction "EN")
			(pintype "input")
		)
		(pad "6" smd rect
			(at 1.299 -0.947 90)
			(size 0.7 1.2)
			(layers "F.Cu" "F.Mask" "F.Paste")
			(net 61 "Net-(U5-BST)")
			(pinfunction "BST")
			(pintype "output")
		)
	)
	(footprint "antmicro-footprints:R_0603_1608Metric"
		(layer "F.Cu")
		(at 141.46 85.5)
		(descr "Resistor SMD 0603")
		(tags "resistor SMD 0603")
		(property "Reference" "R136"
			(at 1.27 0.44 0)
			(layer "F.SilkS")
			(effects
				(font
					(size 0.65 0.65)
					(thickness 0.15)
				)
				(justify left bottom)
			)
		)
		(property "Value" "R_200R_0603"
			(at 0 1.6 0)
			(layer "F.Fab")
			(hide yes)
			(effects
				(font
					(size 0.7 0.7)
					(thickness 0.15)
				)
				(justify left bottom)
			)
		)
		(property "Datasheet" "https://www.bourns.com/docs/product-datasheets/cr.pdf"
			(at 0 0 0)
			(layer "F.Fab")
			(hide yes)
			(effects
				(font
					(size 1.27 1.27)
					(thickness 0.15)
				)
			)
		)
		(property "Description" "SMD Chip Resistor, 200 ohm, ± 1%, 100 mW, 0603 [1608 Metric], Thick Film, General Purpose"
			(at 0 0 0)
			(layer "F.Fab")
			(hide yes)
			(effects
				(font
					(size 1.27 1.27)
					(thickness 0.15)
				)
			)
		)
		(property "Author" "Antmicro"
			(at 0 0 0)
			(layer "F.Fab")
			(hide yes)
			(effects
				(font
					(size 1 1)
					(thickness 0.15)
				)
			)
		)
		(property "License" "Apache-2.0"
			(at 0 0 0)
			(layer "F.Fab")
			(hide yes)
			(effects
				(font
					(size 1 1)
					(thickness 0.15)
				)
			)
		)
		(property "MPN" "CR0603-FX-2000ELF"
			(at 0 0 0)
			(layer "F.Fab")
			(hide yes)
			(effects
				(font
					(size 1 1)
					(thickness 0.15)
				)
			)
		)
		(property "Manufacturer" "Bourns"
			(at 0 0 0)
			(layer "F.Fab")
			(hide yes)
			(effects
				(font
					(size 1 1)
					(thickness 0.15)
				)
			)
		)
		(property "Tolerance" "1%"
			(at 0 0 0)
			(layer "F.Fab")
			(hide yes)
			(effects
				(font
					(size 1 1)
					(thickness 0.15)
				)
			)
		)
		(property "Val" "200R"
			(at 0 0 0)
			(layer "F.Fab")
			(hide yes)
			(effects
				(font
					(size 1 1)
					(thickness 0.15)
				)
			)
		)
		(sheetname "/Peripherals/")
		(sheetfile "peripherals.kicad_sch")
		(attr smd)
		(fp_line
			(start -0.15 -0.4)
			(end 0.15 -0.4)
			(stroke
				(width 0.15)
				(type solid)
			)
			(layer "F.SilkS")
		)
		(fp_line
			(start -0.15 0.4)
			(end 0.15 0.4)
			(stroke
				(width 0.15)
				(type solid)
			)
			(layer "F.SilkS")
		)
		(fp_rect
			(start -1.25 -0.65)
			(end 1.25 0.65)
			(stroke
				(width 0.05)
				(type solid)
			)
			(fill no)
			(layer "F.CrtYd")
		)
		(fp_rect
			(start -0.8 -0.4)
			(end 0.8 0.4)
			(stroke
				(width 0.15)
				(type solid)
			)
			(fill no)
			(layer "F.Fab")
		)
		(fp_text user "${REFERENCE}"
			(at -1.25 3.898 0)
			(layer "F.Fab")
			(effects
				(font
					(size 0.7 0.7)
					(thickness 0.15)
				)
				(justify left bottom)
			)
		)
		(fp_text user "Author: Antmicro"
			(at -1.25 4.9 0)
			(layer "F.Fab")
			(effects
				(font
					(size 0.7 0.7)
					(thickness 0.15)
				)
				(justify left bottom)
			)
		)
		(fp_text user "License: Apache-2.0"
			(at -1.25 5.9 0)
			(layer "F.Fab")
			(effects
				(font
					(size 0.7 0.7)
					(thickness 0.15)
				)
				(justify left bottom)
			)
		)
		(pad "1" smd roundrect
			(at -0.7 0)
			(size 0.8 1)
			(layers "F.Cu" "F.Mask" "F.Paste")
			(roundrect_rratio 0.2)
			(net 295 "Net-(D13-A)")
			(pintype "passive")
		)
		(pad "2" smd roundrect
			(at 0.7 0)
			(size 0.8 1)
			(layers "F.Cu" "F.Mask" "F.Paste")
			(roundrect_rratio 0.2)
			(net 348 "/Peripherals/FTDI_VCCIO")
			(pintype "passive")
		)
	)
	(footprint "antmicro-footprints:TP_SMD_0.75mm"
		(layer "F.Cu")
		(at 99 68.25)
		(property "Reference" "TP26"
			(at -3.22 0.39 0)
			(layer "F.SilkS")
			(effects
				(font
					(size 0.65 0.65)
					(thickness 0.15)
				)
				(justify left bottom)
			)
		)
		(property "Value" "TP_0.75mm_SMD"
			(at 0 1.2 0)
			(layer "F.Fab")
			(hide yes)
			(effects
				(font
					(size 0.7 0.7)
					(thickness 0.15)
				)
				(justify left bottom)
			)
		)
		(property "Description" "SMT test point"
			(at 0 0 0)
			(layer "F.Fab")
			(hide yes)
			(effects
				(font
					(size 1.27 1.27)
					(thickness 0.15)
				)
			)
		)
		(property "Author" "Antmicro"
			(at 0 0 0)
			(layer "F.Fab")
			(hide yes)
			(effects
				(font
					(size 1 1)
					(thickness 0.15)
				)
			)
		)
		(property "License" "Apache-2.0"
			(at 0 0 0)
			(layer "F.Fab")
			(hide yes)
			(effects
				(font
					(size 1 1)
					(thickness 0.15)
				)
			)
		)
		(property "MPN" ""
			(at 0 0 0)
			(layer "F.Fab")
			(hide yes)
			(effects
				(font
					(size 1 1)
					(thickness 0.15)
				)
			)
		)
		(property "Manufacturer" ""
			(at 0 0 0)
			(layer "F.Fab")
			(hide yes)
			(effects
				(font
					(size 1 1)
					(thickness 0.15)
				)
			)
		)
		(sheetname "/SDI/")
		(sheetfile "sdi.kicad_sch")
		(attr exclude_from_pos_files)
		(fp_circle
			(center 0 0)
			(end 0.475 0)
			(stroke
				(width 0.05)
				(type default)
			)
			(fill no)
			(layer "F.CrtYd")
		)
		(fp_text user "License: Apache-2.0"
			(at -0.4 5.101 0)
			(layer "F.Fab")
			(effects
				(font
					(size 0.7 0.7)
					(thickness 0.15)
				)
				(justify left bottom)
			)
		)
		(fp_text user "${REFERENCE}"
			(at -0.4 2.7 0)
			(layer "F.Fab")
			(effects
				(font
					(size 0.7 0.7)
					(thickness 0.15)
				)
				(justify left bottom)
			)
		)
		(fp_text user "Author: Antmicro"
			(at -0.4 3.901 0)
			(layer "F.Fab")
			(effects
				(font
					(size 0.7 0.7)
					(thickness 0.15)
				)
				(justify left bottom)
			)
		)
		(pad "1" smd circle
			(at 0 0)
			(size 0.75 0.75)
			(layers "F.Cu" "F.Mask")
			(net 212 "/SDI/SDI_STAT2")
			(pinfunction "1")
			(pintype "passive")
		)
	)
	(footprint "antmicro-footprints:R_0402_1005Metric"
		(layer "F.Cu")
		(at 167.2 93.6)
		(descr "Resistor SMD 0402")
		(tags "resistor SMD 0402")
		(property "Reference" "R122"
			(at -3.67 0.34 0)
			(layer "F.SilkS")
			(effects
				(font
					(size 0.65 0.65)
					(thickness 0.15)
				)
				(justify left bottom)
			)
		)
		(property "Value" "R_0R_0402"
			(at 0 1.4 0)
			(layer "F.Fab")
			(hide yes)
			(effects
				(font
					(size 0.7 0.7)
					(thickness 0.15)
				)
				(justify left bottom)
			)
		)
		(property "Datasheet" "https://industrial.panasonic.com/cdbs/www-data/pdf/RDA0000/AOA0000C301.pdf"
			(at 0 0 0)
			(layer "F.Fab")
			(hide yes)
			(effects
				(font
					(size 1.27 1.27)
					(thickness 0.15)
				)
			)
		)
		(property "Description" "SMD Chip Resistor, Jumper, 0 ohm, 100 mW, 0402 [1005 Metric], Thick Film, General Purpose"
			(at 0 0 0)
			(layer "F.Fab")
			(hide yes)
			(effects
				(font
					(size 1.27 1.27)
					(thickness 0.15)
				)
			)
		)
		(property "Author" "Antmicro"
			(at 0 0 0)
			(layer "F.Fab")
			(hide yes)
			(effects
				(font
					(size 1 1)
					(thickness 0.15)
				)
			)
		)
		(property "Current" "1A"
			(at 0 0 0)
			(layer "F.Fab")
			(hide yes)
			(effects
				(font
					(size 1 1)
					(thickness 0.15)
				)
			)
		)
		(property "License" "Apache-2.0"
			(at 0 0 0)
			(layer "F.Fab")
			(hide yes)
			(effects
				(font
					(size 1 1)
					(thickness 0.15)
				)
			)
		)
		(property "MPN" "ERJ2GE0R00X"
			(at 0 0 0)
			(layer "F.Fab")
			(hide yes)
			(effects
				(font
					(size 1 1)
					(thickness 0.15)
				)
			)
		)
		(property "Manufacturer" "Panasonic"
			(at 0 0 0)
			(layer "F.Fab")
			(hide yes)
			(effects
				(font
					(size 1 1)
					(thickness 0.15)
				)
			)
		)
		(property "Tolerance" "~"
			(at 0 0 0)
			(layer "F.Fab")
			(hide yes)
			(effects
				(font
					(size 1 1)
					(thickness 0.15)
				)
			)
		)
		(property "Val" "0R"
			(at 0 0 0)
			(layer "F.Fab")
			(hide yes)
			(effects
				(font
					(size 1 1)
					(thickness 0.15)
				)
			)
		)
		(sheetname "/Peripherals/")
		(sheetfile "peripherals.kicad_sch")
		(attr smd)
		(fp_rect
			(start -0.925 -0.47)
			(end 0.925 0.47)
			(stroke
				(width 0.05)
				(type default)
			)
			(fill no)
			(layer "F.CrtYd")
		)
		(fp_rect
			(start -0.5 -0.25)
			(end 0.5 0.25)
			(stroke
				(width 0.15)
				(type solid)
			)
			(fill no)
			(layer "F.Fab")
		)
		(fp_text user "Author: Antmicro"
			(at -0.95 4.169 0)
			(layer "F.Fab")
			(effects
				(font
					(size 0.7 0.7)
					(thickness 0.15)
				)
				(justify left bottom)
			)
		)
		(fp_text user "${REFERENCE}"
			(at -0.95 3.168 0)
			(layer "F.Fab")
			(effects
				(font
					(size 0.7 0.7)
					(thickness 0.15)
				)
				(justify left bottom)
			)
		)
		(fp_text user "License: Apache-2.0"
			(at -0.95 5.169 0)
			(layer "F.Fab")
			(effects
				(font
					(size 0.7 0.7)
					(thickness 0.15)
				)
				(justify left bottom)
			)
		)
		(pad "1" smd roundrect
			(at -0.48 0)
			(size 0.59 0.64)
			(layers "F.Cu" "F.Mask" "F.Paste")
			(roundrect_rratio 0.25)
			(net 91 "/Peripherals/FCC1_SDA1")
			(pintype "passive")
		)
		(pad "2" smd roundrect
			(at 0.48 0)
			(size 0.59 0.64)
			(layers "F.Cu" "F.Mask" "F.Paste")
			(roundrect_rratio 0.25)
			(net 342 "Net-(J4-Pad39)")
			(pintype "passive")
		)
	)
)
